(kicad_pcb
	(version 20241229)
	(generator "pcbnew")
	(generator_version "9.0")
	(general
		(thickness 1.6642)
		(legacy_teardrops no)
	)
	(paper "A3")
	(title_block
		(title "PolarFire SoM")
		(date "2025-07-22")
		(rev "1.1.4")
		(company "Antmicro Ltd")
		(comment 1 "www.antmicro.com")
		(comment 9 "footprints 104-106 of 470")
	)
	(layers
		(0 "F.Cu" mixed)
		(4 "In1.Cu" power)
		(6 "In2.Cu" signal)
		(8 "In3.Cu" power)
		(10 "In4.Cu" signal)
		(12 "In5.Cu" power)
		(14 "In6.Cu" power)
		(16 "In7.Cu" signal)
		(18 "In8.Cu" power)
		(20 "In9.Cu" signal)
		(22 "In10.Cu" power)
		(24 "In11.Cu" signal)
		(26 "In12.Cu" signal)
		(2 "B.Cu" mixed)
		(9 "F.Adhes" user "F.Adhesive")
		(11 "B.Adhes" user "B.Adhesive")
		(13 "F.Paste" user)
		(15 "B.Paste" user)
		(5 "F.SilkS" user "F.Silkscreen")
		(7 "B.SilkS" user "B.Silkscreen")
		(1 "F.Mask" user)
		(3 "B.Mask" user)
		(17 "Dwgs.User" user "User.Drawings")
		(19 "Cmts.User" user "User.Comments")
		(21 "Eco1.User" user "User.Eco1")
		(23 "Eco2.User" user "User.Eco2")
		(25 "Edge.Cuts" user)
		(27 "Margin" user)
		(31 "F.CrtYd" user "F.Courtyard")
		(29 "B.CrtYd" user "B.Courtyard")
		(35 "F.Fab" user)
		(33 "B.Fab" user)
	)
	(footprint "antmicro-footprints:QFN-24-1EP_4x4mm_P0.5_EP2.5x2.5mm"
		(layer "F.Cu")
		(at 214.865 142.4 90)
		(property "Reference" "U13"
			(at 0.28 3.185 270)
			(layer "F.SilkS")
			(effects
				(font
					(size 0.7 0.7)
					(thickness 0.15)
				)
				(justify left bottom)
			)
		)
		(property "Value" "USB3315-CP-TR"
			(at 0 3.4 90)
			(layer "F.Fab")
			(hide yes)
			(effects
				(font
					(size 0.7 0.7)
					(thickness 0.15)
				)
				(justify left bottom)
			)
		)
		(property "Datasheet" "https://ww1.microchip.com/downloads/aemDocuments/documents/OTH/ProductDocuments/DataSheets/00002364A.pdf"
			(at 0 0 90)
			(layer "F.Fab")
			(hide yes)
			(effects
				(font
					(size 1.27 1.27)
					(thickness 0.15)
				)
			)
		)
		(property "Description" "USB Interface, USB PHY Transceiver, USB 2.0, 3 V, 5.5 V, QFN, 24 Pins"
			(at 0 0 90)
			(layer "F.Fab")
			(hide yes)
			(effects
				(font
					(size 1.27 1.27)
					(thickness 0.15)
				)
			)
		)
		(property "Author" "Antmicro"
			(at 357.265 -72.465 0)
			(layer "F.Fab")
			(hide yes)
			(effects
				(font
					(size 1 1)
					(thickness 0.15)
				)
			)
		)
		(property "License" "Apache-2.0"
			(at 357.265 -72.465 0)
			(layer "F.Fab")
			(hide yes)
			(effects
				(font
					(size 1 1)
					(thickness 0.15)
				)
			)
		)
		(property "MPN" "USB3315-CP-TR"
			(at 357.265 -72.465 0)
			(layer "F.Fab")
			(hide yes)
			(effects
				(font
					(size 1 1)
					(thickness 0.15)
				)
			)
		)
		(property "Manufacturer" "Microchip Technology"
			(at 357.265 -72.465 0)
			(layer "F.Fab")
			(hide yes)
			(effects
				(font
					(size 1 1)
					(thickness 0.15)
				)
			)
		)
		(sheetname "/USB/")
		(sheetfile "usb.kicad_sch")
		(attr smd)
		(fp_line
			(start 2.108 -2.11)
			(end 2.108 -1.635)
			(stroke
				(width 0.15)
				(type solid)
			)
			(layer "F.SilkS")
		)
		(fp_line
			(start 1.634 -2.11)
			(end 2.108 -2.11)
			(stroke
				(width 0.15)
				(type solid)
			)
			(layer "F.SilkS")
		)
		(fp_line
			(start -1.635 -2.11)
			(end -2.11 -2.11)
			(stroke
				(width 0.15)
				(type solid)
			)
			(layer "F.SilkS")
		)
		(fp_line
			(start -2.11 -1.636)
			(end -2.11 -2.11)
			(stroke
				(width 0.15)
				(type solid)
			)
			(layer "F.SilkS")
		)
		(fp_line
			(start 2.108 2.108)
			(end 2.108 1.634)
			(stroke
				(width 0.15)
				(type solid)
			)
			(layer "F.SilkS")
		)
		(fp_line
			(start 1.634 2.108)
			(end 2.108 2.108)
			(stroke
				(width 0.15)
				(type solid)
			)
			(layer "F.SilkS")
		)
		(fp_line
			(start -1.635 2.108)
			(end -2.11 2.108)
			(stroke
				(width 0.15)
				(type solid)
			)
			(layer "F.SilkS")
		)
		(fp_line
			(start -2.11 2.108)
			(end -2.11 1.634)
			(stroke
				(width 0.15)
				(type solid)
			)
			(layer "F.SilkS")
		)
		(fp_circle
			(center -2.3 -2.3)
			(end -2.25 -2.3)
			(stroke
				(width 0.15)
				(type solid)
			)
			(fill yes)
			(layer "F.SilkS")
		)
		(fp_rect
			(start -2.503 -2.503)
			(end 2.5 2.5)
			(stroke
				(width 0.05)
				(type solid)
			)
			(fill no)
			(layer "F.CrtYd")
		)
		(fp_line
			(start 1.999 -2)
			(end 1.999 1.999)
			(stroke
				(width 0.15)
				(type solid)
			)
			(layer "F.Fab")
		)
		(fp_line
			(start -1 -2)
			(end 1.999 -2)
			(stroke
				(width 0.15)
				(type solid)
			)
			(layer "F.Fab")
		)
		(fp_line
			(start -2 -1)
			(end -1 -2)
			(stroke
				(width 0.15)
				(type solid)
			)
			(layer "F.Fab")
		)
		(fp_line
			(start 1.999 1.999)
			(end -2 1.999)
			(stroke
				(width 0.15)
				(type solid)
			)
			(layer "F.Fab")
		)
		(fp_line
			(start -2 1.999)
			(end -2 -1)
			(stroke
				(width 0.15)
				(type solid)
			)
			(layer "F.Fab")
		)
		(fp_text user "Author: Antmicro"
			(at -2.503 7.8 90)
			(layer "F.Fab")
			(effects
				(font
					(size 0.7 0.7)
					(thickness 0.15)
				)
				(justify left bottom)
			)
		)
		(fp_text user "License: Apache-2.0"
			(at -2.503 6.6 90)
			(layer "F.Fab")
			(effects
				(font
					(size 0.7 0.7)
					(thickness 0.15)
				)
				(justify left bottom)
			)
		)
		(fp_text user "${REFERENCE}"
			(at -2.503 5.4 90)
			(layer "F.Fab")
			(effects
				(font
					(size 0.7 0.7)
					(thickness 0.15)
				)
				(justify left bottom)
			)
		)
		(pad "" smd roundrect
			(at -0.5 -0.5 90)
			(size 0.8 0.8)
			(layers "F.Paste")
			(roundrect_rratio 0.238095)
		)
		(pad "" smd roundrect
			(at -0.5 0.5 90)
			(size 0.8 0.8)
			(layers "F.Paste")
			(roundrect_rratio 0.238095)
		)
		(pad "" smd roundrect
			(at 0.5 -0.5 90)
			(size 0.8 0.8)
			(layers "F.Paste")
			(roundrect_rratio 0.238095)
		)
		(pad "" smd roundrect
			(at 0.5 0.5 90)
			(size 0.8 0.8)
			(layers "F.Paste")
			(roundrect_rratio 0.238095)
		)
		(pad "1" smd roundrect
			(at -1.938 -1.25 90)
			(size 0.825 0.28)
			(layers "F.Cu" "F.Mask" "F.Paste")
			(roundrect_rratio 0.25)
			(net 62 "USB_OTG_ID")
			(pinfunction "ID")
			(pintype "input")
		)
		(pad "2" smd roundrect
			(at -1.938 -0.75 90)
			(size 0.825 0.28)
			(layers "F.Cu" "F.Mask" "F.Paste")
			(roundrect_rratio 0.25)
			(net 221 "VBUS")
			(pinfunction "VBUS")
			(pintype "bidirectional")
		)
		(pad "3" smd roundrect
			(at -1.938 -0.25 90)
			(size 0.825 0.28)
			(layers "F.Cu" "F.Mask" "F.Paste")
			(roundrect_rratio 0.25)
			(net 50 "+3V3")
			(pinfunction "VBAT")
			(pintype "power_in")
		)
		(pad "4" smd roundrect
			(at -1.938 0.248 90)
			(size 0.825 0.28)
			(layers "F.Cu" "F.Mask" "F.Paste")
			(roundrect_rratio 0.25)
			(net 153 "/USB/VDD33")
			(pinfunction "VDD33")
			(pintype "power_out")
		)
		(pad "5" smd roundrect
			(at -1.938 0.748 90)
			(size 0.825 0.28)
			(layers "F.Cu" "F.Mask" "F.Paste")
			(roundrect_rratio 0.25)
			(net 498 "/USB/USB_N")
			(pinfunction "D_N")
			(pintype "bidirectional")
		)
		(pad "6" smd roundrect
			(at -1.938 1.249 90)
			(size 0.825 0.28)
			(layers "F.Cu" "F.Mask" "F.Paste")
			(roundrect_rratio 0.25)
			(net 499 "/USB/USB_P")
			(pinfunction "D_P")
			(pintype "bidirectional")
		)
		(pad "7" smd roundrect
			(at -1.25 1.937 90)
			(size 0.28 0.825)
			(layers "F.Cu" "F.Mask" "F.Paste")
			(roundrect_rratio 0.25)
			(net 330 "Net-(U13-CPEN)")
			(pinfunction "CPEN")
			(pintype "output")
		)
		(pad "8" smd roundrect
			(at -0.75 1.937 90)
			(size 0.28 0.825)
			(layers "F.Cu" "F.Mask" "F.Paste")
			(roundrect_rratio 0.25)
			(net 642 "/FPGA GPIO/ULPI.DATA7")
			(pinfunction "DATA7")
			(pintype "bidirectional")
		)
		(pad "9" smd roundrect
			(at -0.25 1.937 90)
			(size 0.28 0.825)
			(layers "F.Cu" "F.Mask" "F.Paste")
			(roundrect_rratio 0.25)
			(net 644 "/FPGA GPIO/ULPI.DATA6")
			(pinfunction "DATA6")
			(pintype "bidirectional")
		)
		(pad "10" smd roundrect
			(at 0.248 1.937 90)
			(size 0.28 0.825)
			(layers "F.Cu" "F.Mask" "F.Paste")
			(roundrect_rratio 0.25)
			(net 638 "/FPGA GPIO/ULPI.DATA5")
			(pinfunction "DATA5")
			(pintype "bidirectional")
		)
		(pad "11" smd roundrect
			(at 0.748 1.937 90)
			(size 0.28 0.825)
			(layers "F.Cu" "F.Mask" "F.Paste")
			(roundrect_rratio 0.25)
			(net 637 "/FPGA GPIO/ULPI.DATA4")
			(pinfunction "DATA4")
			(pintype "bidirectional")
		)
		(pad "12" smd roundrect
			(at 1.249 1.937 90)
			(size 0.28 0.825)
			(layers "F.Cu" "F.Mask" "F.Paste")
			(roundrect_rratio 0.25)
			(net 279 "Net-(U13-CLKOUT)")
			(pinfunction "CLKOUT")
			(pintype "output")
		)
		(pad "13" smd roundrect
			(at 1.937 1.249 90)
			(size 0.825 0.28)
			(layers "F.Cu" "F.Mask" "F.Paste")
			(roundrect_rratio 0.25)
			(net 643 "/FPGA GPIO/ULPI.DATA3")
			(pinfunction "DATA3")
			(pintype "bidirectional")
		)
		(pad "14" smd roundrect
			(at 1.937 0.748 90)
			(size 0.825 0.28)
			(layers "F.Cu" "F.Mask" "F.Paste")
			(roundrect_rratio 0.25)
			(net 645 "/FPGA GPIO/ULPI.DATA2")
			(pinfunction "DATA2")
			(pintype "bidirectional")
		)
		(pad "15" smd roundrect
			(at 1.937 0.248 90)
			(size 0.825 0.28)
			(layers "F.Cu" "F.Mask" "F.Paste")
			(roundrect_rratio 0.25)
			(net 639 "/FPGA GPIO/ULPI.DATA1")
			(pinfunction "DATA1")
			(pintype "bidirectional")
		)
		(pad "16" smd roundrect
			(at 1.937 -0.25 90)
			(size 0.825 0.28)
			(layers "F.Cu" "F.Mask" "F.Paste")
			(roundrect_rratio 0.25)
			(net 641 "/FPGA GPIO/ULPI.DATA0")
			(pinfunction "DATA0")
			(pintype "bidirectional")
		)
		(pad "17" smd roundrect
			(at 1.937 -0.75 90)
			(size 0.825 0.28)
			(layers "F.Cu" "F.Mask" "F.Paste")
			(roundrect_rratio 0.25)
			(net 152 "/USB/VDDIO")
			(pinfunction "VDDIO")
			(pintype "power_in")
		)
		(pad "18" smd roundrect
			(at 1.937 -1.25 90)
			(size 0.825 0.28)
			(layers "F.Cu" "F.Mask" "F.Paste")
			(roundrect_rratio 0.25)
			(net 647 "/FPGA GPIO/ULPI.NXT")
			(pinfunction "NXT")
			(pintype "output")
		)
		(pad "19" smd roundrect
			(at 1.249 -1.938 90)
			(size 0.28 0.825)
			(layers "F.Cu" "F.Mask" "F.Paste")
			(roundrect_rratio 0.25)
			(net 640 "/FPGA GPIO/ULPI.DIR")
			(pinfunction "DIR")
			(pintype "output")
		)
		(pad "20" smd roundrect
			(at 0.748 -1.938 90)
			(size 0.28 0.825)
			(layers "F.Cu" "F.Mask" "F.Paste")
			(roundrect_rratio 0.25)
			(net 646 "/FPGA GPIO/ULPI.STP")
			(pinfunction "STP")
			(pintype "input")
		)
		(pad "21" smd roundrect
			(at 0.248 -1.938 90)
			(size 0.28 0.825)
			(layers "F.Cu" "F.Mask" "F.Paste")
			(roundrect_rratio 0.25)
			(net 48 "+1V8")
			(pinfunction "VDD18")
			(pintype "power_out")
		)
		(pad "22" smd roundrect
			(at -0.25 -1.938 90)
			(size 0.28 0.825)
			(layers "F.Cu" "F.Mask" "F.Paste")
			(roundrect_rratio 0.25)
			(net 379 "/USB/RESETB")
			(pinfunction "RESETB")
			(pintype "input")
		)
		(pad "23" smd roundrect
			(at -0.75 -1.938 90)
			(size 0.28 0.825)
			(layers "F.Cu" "F.Mask" "F.Paste")
			(roundrect_rratio 0.25)
			(net 500 "/USB/REF_CLK")
			(pinfunction "REFCLK")
			(pintype "input")
		)
		(pad "24" smd roundrect
			(at -1.25 -1.938 90)
			(size 0.28 0.825)
			(layers "F.Cu" "F.Mask" "F.Paste")
			(roundrect_rratio 0.25)
			(net 280 "Net-(U13-RBIAS)")
			(pinfunction "RBIAS")
			(pintype "passive")
		)
		(pad "25" smd rect
			(at 0 0 90)
			(size 2.5 2.5)
			(layers "F.Cu" "F.Mask")
			(net 417 "GND")
			(pinfunction "GND")
			(pintype "power_in")
		)
	)
	(footprint "antmicro-footprints:TP_SMD_0.75mm"
		(layer "F.Cu")
		(at 227.2 147.18)
		(property "Reference" "TP27"
			(at 10.4 2.57 0)
			(layer "F.SilkS")
			(hide yes)
			(effects
				(font
					(size 0.7 0.7)
					(thickness 0.15)
				)
				(justify left bottom)
			)
		)
		(property "Value" "TP_0.75mm_SMD"
			(at 0 1.2 0)
			(layer "F.Fab")
			(hide yes)
			(effects
				(font
					(size 0.7 0.7)
					(thickness 0.15)
				)
				(justify left bottom)
			)
		)
		(property "Description" "SMT test point"
			(at 0 0 0)
			(layer "F.Fab")
			(hide yes)
			(effects
				(font
					(size 1.27 1.27)
					(thickness 0.15)
				)
			)
		)
		(property "Author" "Antmicro"
			(at 0 0 0)
			(layer "F.Fab")
			(hide yes)
			(effects
				(font
					(size 1 1)
					(thickness 0.15)
				)
			)
		)
		(property "License" "Apache-2.0"
			(at 0 0 0)
			(layer "F.Fab")
			(hide yes)
			(effects
				(font
					(size 1 1)
					(thickness 0.15)
				)
			)
		)
		(property "MPN" ""
			(at 0 0 0)
			(layer "F.Fab")
			(hide yes)
			(effects
				(font
					(size 1 1)
					(thickness 0.15)
				)
			)
		)
		(property "Manufacturer" ""
			(at 0 0 0)
			(layer "F.Fab")
			(hide yes)
			(effects
				(font
					(size 1 1)
					(thickness 0.15)
				)
			)
		)
		(property "Public" "False"
			(at 0 0 0)
			(layer "F.Fab")
			(hide yes)
			(effects
				(font
					(size 1 1)
					(thickness 0.15)
				)
			)
		)
		(sheetname "/WiFi_Bluetooth/")
		(sheetfile "wifi_bt.kicad_sch")
		(attr exclude_from_pos_files exclude_from_bom)
		(fp_circle
			(center 0 0)
			(end 0.475 0)
			(stroke
				(width 0.05)
				(type default)
			)
			(fill no)
			(layer "F.CrtYd")
		)
		(fp_text user "Author: Antmicro"
			(at -0.4 3.901 0)
			(layer "F.Fab")
			(effects
				(font
					(size 0.7 0.7)
					(thickness 0.15)
				)
				(justify left bottom)
			)
		)
		(fp_text user "${REFERENCE}"
			(at -0.4 2.7 0)
			(layer "F.Fab")
			(effects
				(font
					(size 0.7 0.7)
					(thickness 0.15)
				)
				(justify left bottom)
			)
		)
		(fp_text user "License: Apache-2.0"
			(at -0.4 5.101 0)
			(layer "F.Fab")
			(effects
				(font
					(size 0.7 0.7)
					(thickness 0.15)
				)
				(justify left bottom)
			)
		)
		(pad "1" smd circle
			(at 0 0)
			(size 0.75 0.75)
			(layers "F.Cu" "F.Mask")
			(net 524 "Net-(U26A-BT_DEV_WAKE)")
			(pinfunction "1")
			(pintype "passive")
		)
	)
	(footprint "antmicro-footprints:L_0805_2012Metric"
		(layer "F.Cu")
		(at 176.9 144.11 -90)
		(descr "Inductor  SMD 0805")
		(tags "inductor SMD 0805")
		(property "Reference" "L4"
			(at 2.596305 -0.675 0)
			(layer "F.SilkS")
			(effects
				(font
					(size 0.7 0.7)
					(thickness 0.15)
				)
				(justify right bottom)
			)
		)
		(property "Value" "L_1u_3.2A_0805"
			(at 0 1.947 90)
			(layer "F.Fab")
			(hide yes)
			(effects
				(font
					(size 0.7 0.7)
					(thickness 0.15)
				)
				(justify right bottom)
			)
		)
		(property "Datasheet" "https://abracon.com/datasheets/AOTA-B201208S.pdf"
			(at 0 0 270)
			(layer "F.Fab")
			(hide yes)
			(effects
				(font
					(size 1.27 1.27)
					(thickness 0.15)
				)
			)
		)
		(property "Description" "Power Inductor (SMT), 1 µH, 0.05 ohm, 3.2 A, AOTA-B201208S"
			(at 0 0 270)
			(layer "F.Fab")
			(hide yes)
			(effects
				(font
					(size 1.27 1.27)
					(thickness 0.15)
				)
			)
		)
		(property "Author" "Antmicro"
			(at 32.79 321.01 0)
			(layer "F.Fab")
			(hide yes)
			(effects
				(font
					(size 1 1)
					(thickness 0.15)
				)
			)
		)
		(property "IMax" "3.2 A"
			(at 32.79 321.01 0)
			(layer "F.Fab")
			(hide yes)
			(effects
				(font
					(size 1 1)
					(thickness 0.15)
				)
			)
		)
		(property "ISat" "3.5 A"
			(at 32.79 321.01 0)
			(layer "F.Fab")
			(hide yes)
			(effects
				(font
					(size 1 1)
					(thickness 0.15)
				)
			)
		)
		(property "License" "Apache-2.0"
			(at 32.79 321.01 0)
			(layer "F.Fab")
			(hide yes)
			(effects
				(font
					(size 1 1)
					(thickness 0.15)
				)
			)
		)
		(property "MPN" "AOTA-B201208S1R0MT "
			(at 32.79 321.01 0)
			(layer "F.Fab")
			(hide yes)
			(effects
				(font
					(size 1 1)
					(thickness 0.15)
				)
			)
		)
		(property "Manufacturer" "Abracon"
			(at 32.79 321.01 0)
			(layer "F.Fab")
			(hide yes)
			(effects
				(font
					(size 1 1)
					(thickness 0.15)
				)
			)
		)
		(property "Public" ""
			(at 32.79 321.01 0)
			(layer "F.Fab")
			(hide yes)
			(effects
				(font
					(size 1 1)
					(thickness 0.15)
				)
			)
		)
		(property "Size" "2x1.2"
			(at 32.79 321.01 0)
			(layer "F.Fab")
			(hide yes)
			(effects
				(font
					(size 1 1)
					(thickness 0.15)
				)
			)
		)
		(property "Val" "1u/3.2A"
			(at 32.79 321.01 0)
			(layer "F.Fab")
			(hide yes)
			(effects
				(font
					(size 1 1)
					(thickness 0.15)
				)
			)
		)
		(sheetname "/Supply/")
		(sheetfile "supply.kicad_sch")
		(attr smd)
		(fp_line
			(start -0.3 0.7)
			(end 0.3 0.7)
			(stroke
				(width 0.15)
				(type solid)
			)
			(layer "F.SilkS")
		)
		(fp_line
			(start -0.3 -0.7)
			(end 0.3 -0.7)
			(stroke
				(width 0.15)
				(type solid)
			)
			(layer "F.SilkS")
		)
		(fp_rect
			(start 1.95 -0.9)
			(end -1.95 0.9)
			(stroke
				(width 0.05)
				(type default)
			)
			(fill no)
			(layer "F.CrtYd")
		)
		(fp_rect
			(start -0.95 -0.675)
			(end 0.95 0.675)
			(stroke
				(width 0.15)
				(type solid)
			)
			(fill no)
			(layer "F.Fab")
		)
		(fp_text user "License: Apache-2.0"
			(at -1.9 4.947 270)
			(layer "F.Fab")
			(effects
				(font
					(size 0.7 0.7)
					(thickness 0.15)
				)
				(justify left bottom)
			)
		)
		(fp_text user "${REFERENCE}"
			(at -1.9 3.947 270)
			(layer "F.Fab")
			(effects
				(font
					(size 0.7 0.7)
					(thickness 0.15)
				)
				(justify left bottom)
			)
		)
		(fp_text user "Author: Antmicro"
			(at -1.9 5.947 270)
			(layer "F.Fab")
			(effects
				(font
					(size 0.7 0.7)
					(thickness 0.15)
				)
				(justify left bottom)
			)
		)
		(pad "1" smd roundrect
			(at -1.1 0 270)
			(size 1.2 1.3)
			(layers "F.Cu" "F.Mask" "F.Paste")
			(roundrect_rratio 0.25)
			(net 181 "Net-(U7-SW3)")
			(pintype "passive")
		)
		(pad "2" smd roundrect
			(at 1.1 0 270)
			(size 1.2 1.3)
			(layers "F.Cu" "F.Mask" "F.Paste")
			(roundrect_rratio 0.25)
			(net 406 "/Supply/SENSE2_P")
			(pintype "passive")
		)
	)
)
